#ISCELL
  mstr_symbols cad_note *
  *
#ISCELL
  mstr_symbols intel_corp_bpage *
  *
#CELL
  mstr_discrete cap *
  page106_i10
#CELL
  mstr_discrete cap *
  page106_i100
#ISCELL
  mstr_standard tap *
  page106_i101
#CELL
  mstr_discrete cap *
  page106_i102
#ISCELL
  mstr_standard tap *
  page106_i103
#ISCELL
  mstr_standard tap *
  page106_i104
#CELL
  mstr_discrete cap *
  page106_i105
#ISCELL
  mstr_standard tap *
  page106_i106
#ISCELL
  mstr_standard offpage *
  page106_i107
#ISCELL
  mstr_standard tap *
  page106_i108
#CELL
  mstr_discrete cap *
  page106_i109
#ISCELL
  mstr_standard tap *
  page106_i11
#ISCELL
  mstr_standard tap *
  page106_i110
#CELL
  mstr_discrete cap *
  page106_i111
#ISCELL
  mstr_standard tap *
  page106_i112
#ISCELL
  mstr_standard tap *
  page106_i113
#CELL
  mstr_discrete cap *
  page106_i114
#ISCELL
  mstr_standard tap *
  page106_i115
#ISCELL
  mstr_standard tap *
  page106_i116
#CELL
  mstr_discrete cap *
  page106_i117
#ISCELL
  mstr_standard tap *
  page106_i118
#ISCELL
  mstr_standard tap *
  page106_i119
#ISCELL
  mstr_standard offpage *
  page106_i120
#ISCELL
  mstr_standard tap *
  page106_i121
#CELL
  mstr_discrete cap *
  page106_i122
#CELL
  mstr_discrete cap *
  page106_i123
#ISCELL
  mstr_standard tap *
  page106_i124
#ISCELL
  mstr_standard tap *
  page106_i125
#ISCELL
  mstr_standard tap *
  page106_i126
#ISCELL
  mstr_standard tap *
  page106_i127
#CELL
  mstr_discrete cap *
  page106_i128
#ISCELL
  mstr_standard tap *
  page106_i129
#CELL
  mstr_discrete cap *
  page106_i130
#ISCELL
  mstr_standard tap *
  page106_i131
#ISCELL
  mstr_standard tap *
  page106_i133
#CELL
  mstr_discrete cap *
  page106_i134
#ISCELL
  mstr_standard tap *
  page106_i135
#ISCELL
  mstr_standard tap *
  page106_i136
#CELL
  mstr_discrete cap *
  page106_i137
#ISCELL
  mstr_standard tap *
  page106_i138
#ISCELL
  mstr_standard tap *
  page106_i140
#CELL
  mstr_discrete cap *
  page106_i141
#CELL
  mstr_discrete cap *
  page106_i142
#ISCELL
  mstr_standard tap *
  page106_i143
#ISCELL
  mstr_standard tap *
  page106_i144
#ISCELL
  mstr_standard tap *
  page106_i145
#ISCELL
  mstr_standard tap *
  page106_i146
#CELL
  mstr_discrete cap *
  page106_i147
#ISCELL
  mstr_standard tap *
  page106_i148
#ISCELL
  mstr_standard offpage *
  page106_i151
#ISCELL
  mstr_standard offpage *
  page106_i152
#ISCELL
  mstr_standard tap *
  page106_i25
#CELL
  mstr_discrete cap *
  page106_i26
#ISCELL
  mstr_standard tap *
  page106_i27
#ISCELL
  mstr_standard tap *
  page106_i28
#CELL
  mstr_discrete cap *
  page106_i29
#ISCELL
  mstr_standard tap *
  page106_i30
#ISCELL
  mstr_standard tap *
  page106_i36
#CELL
  mstr_discrete cap *
  page106_i37
#ISCELL
  mstr_standard tap *
  page106_i38
#ISCELL
  mstr_standard tap *
  page106_i39
#CELL
  mstr_discrete cap *
  page106_i40
#ISCELL
  mstr_standard tap *
  page106_i41
#ISCELL
  mstr_standard tap *
  page106_i54
#CELL
  mstr_discrete cap *
  page106_i55
#ISCELL
  mstr_standard tap *
  page106_i56
#ISCELL
  mstr_standard tap *
  page106_i58
#CELL
  mstr_discrete cap *
  page106_i59
#ISCELL
  mstr_standard tap *
  page106_i60
#ISCELL
  mstr_standard tap *
  page106_i69
#CELL
  mstr_discrete cap *
  page106_i70
#ISCELL
  mstr_standard tap *
  page106_i72
#ISCELL
  mstr_standard tap *
  page106_i73
#ISCELL
  mstr_standard tap *
  page106_i74
#ISCELL
  mstr_standard tap *
  page106_i75
#CELL
  mstr_discrete cap *
  page106_i76
#ISCELL
  mstr_standard tap *
  page106_i77
#CELL
  mstr_discrete cap *
  page106_i78
#ISCELL
  mstr_standard tap *
  page106_i79
#ISCELL
  mstr_standard tap *
  page106_i80
#ISCELL
  mstr_standard tap *
  page106_i81
#CELL
  mstr_discrete cap *
  page106_i82
#ISCELL
  mstr_standard tap *
  page106_i83
#ISCELL
  mstr_standard tap *
  page106_i84
#CELL
  mstr_discrete cap *
  page106_i85
#CELL
  mstr_discrete cap *
  page106_i86
#ISCELL
  mstr_standard tap *
  page106_i87
#ISCELL
  mstr_standard tap *
  page106_i88
#ISCELL
  mstr_standard tap *
  page106_i89
#ISCELL
  mstr_standard tap *
  page106_i9
#CELL
  mstr_discrete cap *
  page106_i90
#ISCELL
  mstr_standard tap *
  page106_i91
#CELL
  mstr_discrete cap *
  page106_i92
#ISCELL
  mstr_standard tap *
  page106_i93
#ISCELL
  mstr_standard tap *
  page106_i94
#CELL
  mstr_discrete cap *
  page106_i95
#ISCELL
  mstr_standard tap *
  page106_i96
#ISCELL
  mstr_standard tap *
  page106_i97
#ISCELL
  mstr_standard tap *
  page106_i98
#ISCELL
  mstr_standard tap *
  page106_i99
